(kicad_pcb
	(version 20241229)
	(generator "pcbnew")
	(generator_version "9.0")
	(general
		(thickness 1.711)
		(legacy_teardrops no)
	)
	(paper "A4")
	(title_block
		(title "Antmicro Baseboard for Jetson AGX Thor")
		(date "2026-02-18")
		(rev "1.1.0")
		(company "Antmicro Ltd")
		(comment 1 "www.antmicro.com")
		(comment 9 "footprints 711-715 of 1170")
	)
	(layers
		(0 "F.Cu" signal)
		(4 "In1.Cu" signal)
		(6 "In2.Cu" signal)
		(8 "In3.Cu" signal)
		(10 "In4.Cu" jumper)
		(12 "In5.Cu" signal)
		(14 "In6.Cu" signal)
		(16 "In7.Cu" signal)
		(18 "In8.Cu" signal)
		(2 "B.Cu" signal)
		(9 "F.Adhes" user "F.Adhesive")
		(11 "B.Adhes" user "B.Adhesive")
		(13 "F.Paste" user)
		(15 "B.Paste" user)
		(5 "F.SilkS" user "F.Silkscreen")
		(7 "B.SilkS" user "B.Silkscreen")
		(1 "F.Mask" user)
		(3 "B.Mask" user)
		(17 "Dwgs.User" user "User.Drawings")
		(19 "Cmts.User" user "User.Comments")
		(21 "Eco1.User" user "User.Eco1")
		(23 "Eco2.User" user "User.Eco2")
		(25 "Edge.Cuts" user)
		(27 "Margin" user)
		(31 "F.CrtYd" user "F.Courtyard")
		(29 "B.CrtYd" user "B.Courtyard")
		(35 "F.Fab" user)
		(33 "B.Fab" user)
	)
	(footprint "antmicro-footprints:R_0402_1005Metric"
		(layer "B.Cu")
		(at 238.095 82.500001 180)
		(descr "Resistor SMD 0402")
		(tags "resistor SMD 0402")
		(property "Reference" "R152"
			(at -1.605 -2.299999 0)
			(layer "B.SilkS")
			(effects
				(font
					(size 0.7 0.7)
					(thickness 0.15)
				)
				(justify left bottom mirror)
			)
		)
		(property "Value" "R_10k_0402"
			(at -1.011843 -1.772046 0)
			(layer "B.Fab")
			(effects
				(font
					(size 0.7 0.7)
					(thickness 0.15)
				)
				(justify left bottom mirror)
			)
		)
		(property "Datasheet" "https://www.bourns.com/docs/product-datasheets/cr.pdf"
			(at 0 0 0)
			(layer "B.Fab")
			(hide yes)
			(effects
				(font
					(size 1.27 1.27)
					(thickness 0.15)
				)
				(justify mirror)
			)
		)
		(property "Description" "SMD Chip Resistor, 10 kohm, ± 1%, 62.5 mW, 0402 [1005 Metric], Thick Film, General Purpose"
			(at 0 0 0)
			(layer "B.Fab")
			(hide yes)
			(effects
				(font
					(size 1.27 1.27)
					(thickness 0.15)
				)
				(justify mirror)
			)
		)
		(property "Manufacturer" "Bourns"
			(at 0 0 0)
			(unlocked yes)
			(layer "B.Fab")
			(hide yes)
			(effects
				(font
					(size 1 1)
					(thickness 0.15)
				)
				(justify mirror)
			)
		)
		(property "MPN" "CR0402-FX-1002GLF"
			(at 0 0 0)
			(unlocked yes)
			(layer "B.Fab")
			(hide yes)
			(effects
				(font
					(size 1 1)
					(thickness 0.15)
				)
				(justify mirror)
			)
		)
		(property "Val" "10k"
			(at 0 0 0)
			(unlocked yes)
			(layer "B.Fab")
			(hide yes)
			(effects
				(font
					(size 1 1)
					(thickness 0.15)
				)
				(justify mirror)
			)
		)
		(property "License" "Apache-2.0"
			(at 0 0 0)
			(unlocked yes)
			(layer "B.Fab")
			(hide yes)
			(effects
				(font
					(size 1 1)
					(thickness 0.15)
				)
				(justify mirror)
			)
		)
		(property "Author" "Antmicro"
			(at 0 0 0)
			(unlocked yes)
			(layer "B.Fab")
			(hide yes)
			(effects
				(font
					(size 1 1)
					(thickness 0.15)
				)
				(justify mirror)
			)
		)
		(property "Tolerance" "1%"
			(at 0 0 0)
			(unlocked yes)
			(layer "B.Fab")
			(hide yes)
			(effects
				(font
					(size 1 1)
					(thickness 0.15)
				)
				(justify mirror)
			)
		)
		(sheetname "/USB Debug, PD/")
		(sheetfile "usb_debug_pd.kicad_sch")
		(attr smd)
		(fp_poly
			(pts
				(xy -0.925 0.47) (xy -0.925 -0.47) (xy 0.925 -0.47) (xy 0.925 0.47)
			)
			(stroke
				(width 0.05)
				(type default)
			)
			(fill no)
			(layer "B.CrtYd")
		)
		(fp_poly
			(pts
				(xy -0.5 0.25) (xy -0.5 -0.25) (xy 0.5 -0.25) (xy 0.5 0.25)
			)
			(stroke
				(width 0.15)
				(type solid)
			)
			(fill no)
			(layer "B.Fab")
		)
		(fp_text user "${REFERENCE}"
			(at -0.95 -3.168 0)
			(layer "B.Fab")
			(effects
				(font
					(size 0.7 0.7)
					(thickness 0.15)
				)
				(justify left bottom mirror)
			)
		)
		(fp_text user "Author: Antmicro"
			(at -0.95 -4.169 0)
			(layer "B.Fab")
			(effects
				(font
					(size 0.7 0.7)
					(thickness 0.15)
				)
				(justify left bottom mirror)
			)
		)
		(fp_text user "License: Apache-2.0"
			(at -0.949999 -5.169 0)
			(layer "B.Fab")
			(effects
				(font
					(size 0.7 0.7)
					(thickness 0.15)
				)
				(justify left bottom mirror)
			)
		)
		(pad "1" smd roundrect
			(at -0.48 0 180)
			(size 0.59 0.64)
			(layers "B.Cu" "B.Mask" "B.Paste")
			(roundrect_rratio 0.25)
			(net 1 "GND")
			(pintype "passive")
		)
		(pad "2" smd roundrect
			(at 0.48 0 180)
			(size 0.59 0.64)
			(layers "B.Cu" "B.Mask" "B.Paste")
			(roundrect_rratio 0.25)
			(net 977 "Net-(U40-EN)")
			(pintype "passive")
		)
	)
	(footprint "antmicro-footprints:R_0402_1005Metric"
		(layer "B.Cu")
		(at 217.55 113.03)
		(descr "Resistor SMD 0402")
		(tags "resistor SMD 0402")
		(property "Reference" "R329"
			(at -1.76 1.79 0)
			(layer "B.SilkS")
			(effects
				(font
					(size 0.7 0.7)
					(thickness 0.15)
				)
				(justify right top mirror)
			)
		)
		(property "Value" "R_10k_0402"
			(at -1.011843 -1.772047 0)
			(layer "B.Fab")
			(effects
				(font
					(size 0.7 0.7)
					(thickness 0.15)
				)
				(justify right top mirror)
			)
		)
		(property "Datasheet" "https://www.bourns.com/docs/product-datasheets/cr.pdf"
			(at 0 0 0)
			(layer "B.Fab")
			(hide yes)
			(effects
				(font
					(size 1.27 1.27)
					(thickness 0.15)
				)
				(justify mirror)
			)
		)
		(property "Description" "SMD Chip Resistor, 10 kohm, ± 1%, 62.5 mW, 0402 [1005 Metric], Thick Film, General Purpose"
			(at 0 0 0)
			(layer "B.Fab")
			(hide yes)
			(effects
				(font
					(size 1.27 1.27)
					(thickness 0.15)
				)
				(justify mirror)
			)
		)
		(property "MPN" "CR0402-FX-1002GLF"
			(at 0 0 180)
			(unlocked yes)
			(layer "B.Fab")
			(hide yes)
			(effects
				(font
					(size 1 1)
					(thickness 0.15)
				)
				(justify mirror)
			)
		)
		(property "Manufacturer" "Bourns"
			(at 0 0 180)
			(unlocked yes)
			(layer "B.Fab")
			(hide yes)
			(effects
				(font
					(size 1 1)
					(thickness 0.15)
				)
				(justify mirror)
			)
		)
		(property "License" "Apache-2.0"
			(at 0 0 180)
			(unlocked yes)
			(layer "B.Fab")
			(hide yes)
			(effects
				(font
					(size 1 1)
					(thickness 0.15)
				)
				(justify mirror)
			)
		)
		(property "Author" "Antmicro"
			(at 0 0 180)
			(unlocked yes)
			(layer "B.Fab")
			(hide yes)
			(effects
				(font
					(size 1 1)
					(thickness 0.15)
				)
				(justify mirror)
			)
		)
		(property "Val" "10k"
			(at 0 0 180)
			(unlocked yes)
			(layer "B.Fab")
			(hide yes)
			(effects
				(font
					(size 1 1)
					(thickness 0.15)
				)
				(justify mirror)
			)
		)
		(property "Tolerance" "1%"
			(at 0 0 180)
			(unlocked yes)
			(layer "B.Fab")
			(hide yes)
			(effects
				(font
					(size 1 1)
					(thickness 0.15)
				)
				(justify mirror)
			)
		)
		(sheetname "/USB Hub/")
		(sheetfile "usb_hub.kicad_sch")
		(attr smd)
		(fp_rect
			(start -0.925 0.47)
			(end 0.925 -0.47)
			(stroke
				(width 0.05)
				(type default)
			)
			(fill no)
			(layer "B.CrtYd")
		)
		(fp_rect
			(start -0.5 0.25)
			(end 0.5 -0.25)
			(stroke
				(width 0.15)
				(type solid)
			)
			(fill no)
			(layer "B.Fab")
		)
		(fp_text user "Author: Antmicro"
			(at -0.95 -4.169 0)
			(layer "B.Fab")
			(effects
				(font
					(size 0.7 0.7)
					(thickness 0.15)
				)
				(justify right top mirror)
			)
		)
		(fp_text user "${REFERENCE}"
			(at -0.95 -3.168 0)
			(layer "B.Fab")
			(effects
				(font
					(size 0.7 0.7)
					(thickness 0.15)
				)
				(justify right top mirror)
			)
		)
		(fp_text user "License: Apache-2.0"
			(at -0.95 -5.169 0)
			(layer "B.Fab")
			(effects
				(font
					(size 0.7 0.7)
					(thickness 0.15)
				)
				(justify right top mirror)
			)
		)
		(pad "1" smd roundrect
			(at -0.48 0)
			(size 0.59 0.64)
			(layers "B.Cu" "B.Mask" "B.Paste")
			(roundrect_rratio 0.25)
			(net 1106 "/USB Hub/DP2_VCONN2")
			(pintype "passive")
		)
		(pad "2" smd roundrect
			(at 0.48 0)
			(size 0.59 0.64)
			(layers "B.Cu" "B.Mask" "B.Paste")
			(roundrect_rratio 0.25)
			(net 1 "GND")
			(pintype "passive")
		)
	)
	(footprint "antmicro-footprints:C_0402_1005Metric"
		(layer "B.Cu")
		(at 127.073 150.344)
		(descr "Capacitor SMD 0402")
		(tags "capacitor SMD 0402")
		(property "Reference" "C204"
			(at -3.773 -0.344 0)
			(layer "B.SilkS")
			(effects
				(font
					(size 0.7 0.7)
					(thickness 0.15)
				)
				(justify right top mirror)
			)
		)
		(property "Value" "C_100n_0402"
			(at -1.022927 -2.155213 0)
			(layer "B.Fab")
			(effects
				(font
					(size 0.7 0.7)
					(thickness 0.15)
				)
				(justify right top mirror)
			)
		)
		(property "Datasheet" "https://www.murata.com/products/productdetail?partno=GRM155R61H104KE14%23"
			(at 0 0 0)
			(layer "B.Fab")
			(hide yes)
			(effects
				(font
					(size 1.27 1.27)
					(thickness 0.15)
				)
				(justify mirror)
			)
		)
		(property "Description" "SMD Multilayer Ceramic Capacitor, 0.1 µF, 50 V, 0402 [1005 Metric], ± 10%, X5R, GRM Series"
			(at 0 0 0)
			(layer "B.Fab")
			(hide yes)
			(effects
				(font
					(size 1.27 1.27)
					(thickness 0.15)
				)
				(justify mirror)
			)
		)
		(property "MPN" "GRM155R61H104KE14D"
			(at 0 0 180)
			(unlocked yes)
			(layer "B.Fab")
			(hide yes)
			(effects
				(font
					(size 1 1)
					(thickness 0.15)
				)
				(justify mirror)
			)
		)
		(property "Val" "100n"
			(at 0 0 180)
			(unlocked yes)
			(layer "B.Fab")
			(hide yes)
			(effects
				(font
					(size 1 1)
					(thickness 0.15)
				)
				(justify mirror)
			)
		)
		(property "Voltage" "50V"
			(at 0 0 180)
			(unlocked yes)
			(layer "B.Fab")
			(hide yes)
			(effects
				(font
					(size 1 1)
					(thickness 0.15)
				)
				(justify mirror)
			)
		)
		(property "Dielectric" "X5R"
			(at 0 0 180)
			(unlocked yes)
			(layer "B.Fab")
			(hide yes)
			(effects
				(font
					(size 1 1)
					(thickness 0.15)
				)
				(justify mirror)
			)
		)
		(property "Manufacturer" "Murata"
			(at 0 0 180)
			(unlocked yes)
			(layer "B.Fab")
			(hide yes)
			(effects
				(font
					(size 1 1)
					(thickness 0.15)
				)
				(justify mirror)
			)
		)
		(property "License" "Apache-2.0"
			(at 0 0 180)
			(unlocked yes)
			(layer "B.Fab")
			(hide yes)
			(effects
				(font
					(size 1 1)
					(thickness 0.15)
				)
				(justify mirror)
			)
		)
		(property "Author" "Antmicro"
			(at 0 0 180)
			(unlocked yes)
			(layer "B.Fab")
			(hide yes)
			(effects
				(font
					(size 1 1)
					(thickness 0.15)
				)
				(justify mirror)
			)
		)
		(sheetname "/Peripherals/")
		(sheetfile "peripherals.kicad_sch")
		(attr smd)
		(fp_rect
			(start -0.925 0.47)
			(end 0.925 -0.47)
			(stroke
				(width 0.05)
				(type default)
			)
			(fill no)
			(layer "B.CrtYd")
		)
		(fp_line
			(start -0.494 -0.248)
			(end -0.494 0.25)
			(stroke
				(width 0.15)
				(type solid)
			)
			(layer "B.Fab")
		)
		(fp_line
			(start -0.494 0.25)
			(end 0.504 0.25)
			(stroke
				(width 0.15)
				(type solid)
			)
			(layer "B.Fab")
		)
		(fp_line
			(start 0.504 -0.248)
			(end -0.494 -0.248)
			(stroke
				(width 0.15)
				(type solid)
			)
			(layer "B.Fab")
		)
		(fp_line
			(start 0.504 0.25)
			(end 0.504 -0.248)
			(stroke
				(width 0.15)
				(type solid)
			)
			(layer "B.Fab")
		)
		(fp_text user "License: Apache-2.0"
			(at -0.939 -5.799 0)
			(layer "B.Fab")
			(effects
				(font
					(size 0.7 0.7)
					(thickness 0.15)
				)
				(justify right top mirror)
			)
		)
		(fp_text user "${REFERENCE}"
			(at -0.939 -4.599 0)
			(layer "B.Fab")
			(effects
				(font
					(size 0.7 0.7)
					(thickness 0.15)
				)
				(justify right top mirror)
			)
		)
		(fp_text user "Author: Antmicro"
			(at -0.939 -3.399 0)
			(layer "B.Fab")
			(effects
				(font
					(size 0.7 0.7)
					(thickness 0.15)
				)
				(justify right top mirror)
			)
		)
		(pad "1" smd roundrect
			(at -0.48 0)
			(size 0.59 0.64)
			(layers "B.Cu" "B.Mask" "B.Paste")
			(roundrect_rratio 0.25)
			(net 1 "GND")
			(pintype "passive")
		)
		(pad "2" smd roundrect
			(at 0.48 0)
			(size 0.59 0.64)
			(layers "B.Cu" "B.Mask" "B.Paste")
			(roundrect_rratio 0.25)
			(net 2 "+3V3")
			(pintype "passive")
		)
	)
	(footprint "antmicro-footprints:TP_SMD_0.75mm"
		(layer "B.Cu")
		(at 143.630532 78.81 90)
		(property "Reference" "TP49"
			(at -0.49 0.369468 90)
			(layer "B.SilkS")
			(effects
				(font
					(size 0.7 0.7)
					(thickness 0.15)
				)
				(justify left bottom mirror)
			)
		)
		(property "Value" "TP_0.75mm_SMD"
			(at 0 -1.2 90)
			(layer "B.Fab")
			(effects
				(font
					(size 0.7 0.7)
					(thickness 0.15)
				)
				(justify right top mirror)
			)
		)
		(property "Description" "SMT test point"
			(at 0 0 90)
			(layer "B.Fab")
			(hide yes)
			(effects
				(font
					(size 1.27 1.27)
					(thickness 0.15)
				)
				(justify mirror)
			)
		)
		(property "MPN" ""
			(at 0 0 270)
			(unlocked yes)
			(layer "B.Fab")
			(hide yes)
			(effects
				(font
					(size 1 1)
					(thickness 0.15)
				)
				(justify mirror)
			)
		)
		(property "Manufacturer" ""
			(at 0 0 270)
			(unlocked yes)
			(layer "B.Fab")
			(hide yes)
			(effects
				(font
					(size 1 1)
					(thickness 0.15)
				)
				(justify mirror)
			)
		)
		(property "Author" "Antmicro"
			(at 0 0 270)
			(unlocked yes)
			(layer "B.Fab")
			(hide yes)
			(effects
				(font
					(size 1 1)
					(thickness 0.15)
				)
				(justify mirror)
			)
		)
		(property "License" "Apache-2.0"
			(at 0 0 270)
			(unlocked yes)
			(layer "B.Fab")
			(hide yes)
			(effects
				(font
					(size 1 1)
					(thickness 0.15)
				)
				(justify mirror)
			)
		)
		(sheetname "/SoM_Power/")
		(sheetfile "som_power.kicad_sch")
		(attr exclude_from_pos_files exclude_from_bom)
		(fp_circle
			(center 0 0)
			(end 0.475 0)
			(stroke
				(width 0.05)
				(type default)
			)
			(fill no)
			(layer "B.CrtYd")
		)
		(fp_text user "${REFERENCE}"
			(at -0.4 -2.7 90)
			(layer "B.Fab")
			(effects
				(font
					(size 0.7 0.7)
					(thickness 0.15)
				)
				(justify right top mirror)
			)
		)
		(fp_text user "License: Apache-2.0"
			(at -0.4 -5.101 90)
			(layer "B.Fab")
			(effects
				(font
					(size 0.7 0.7)
					(thickness 0.15)
				)
				(justify right top mirror)
			)
		)
		(fp_text user "Author: Antmicro"
			(at -0.4 -3.901 90)
			(layer "B.Fab")
			(effects
				(font
					(size 0.7 0.7)
					(thickness 0.15)
				)
				(justify right top mirror)
			)
		)
		(pad "1" smd circle
			(at 0 0 90)
			(size 0.75 0.75)
			(layers "B.Cu" "B.Mask")
			(net 678 "Net-(J1A-VCOMP_ALERT_N)")
			(pinfunction "1")
			(pintype "passive")
		)
	)
	(footprint "antmicro-footprints:C_0805_2012Metric"
		(layer "B.Cu")
		(at 99.1 136.6 90)
		(descr "Capacitor SMD 0805")
		(tags "capacitor SMD 0805")
		(property "Reference" "C50"
			(at -2.10551 1.198678 90)
			(layer "B.SilkS")
			(effects
				(font
					(size 0.7 0.7)
					(thickness 0.15)
				)
				(justify right top mirror)
			)
		)
		(property "Value" "C_22u_25V_0805"
			(at -2.055717 -1.963153 90)
			(layer "B.Fab")
			(effects
				(font
					(size 0.7 0.7)
					(thickness 0.15)
				)
				(justify right top mirror)
			)
		)
		(property "Datasheet" "https://product.samsungsem.com/mlcc/CL21A226MAYNNN.do"
			(at 0 0 90)
			(layer "B.Fab")
			(hide yes)
			(effects
				(font
					(size 1.27 1.27)
					(thickness 0.15)
				)
				(justify mirror)
			)
		)
		(property "Description" "SMT Multilayer Ceramic Capacitor, 22uF, +/-20%, 25V, X5R, 0805 [2012 Metric]"
			(at 0 0 90)
			(layer "B.Fab")
			(hide yes)
			(effects
				(font
					(size 1.27 1.27)
					(thickness 0.15)
				)
				(justify mirror)
			)
		)
		(property "MPN" "CL21A226MAYNNNE"
			(at 0 0 90)
			(unlocked yes)
			(layer "B.Fab")
			(hide yes)
			(effects
				(font
					(size 1 1)
					(thickness 0.15)
				)
				(justify mirror)
			)
		)
		(property "Val" "22u"
			(at 0 0 90)
			(unlocked yes)
			(layer "B.Fab")
			(hide yes)
			(effects
				(font
					(size 1 1)
					(thickness 0.15)
				)
				(justify mirror)
			)
		)
		(property "Voltage" "25V"
			(at 0 0 90)
			(unlocked yes)
			(layer "B.Fab")
			(hide yes)
			(effects
				(font
					(size 1 1)
					(thickness 0.15)
				)
				(justify mirror)
			)
		)
		(property "Dielectric" "X5R"
			(at 0 0 90)
			(unlocked yes)
			(layer "B.Fab")
			(hide yes)
			(effects
				(font
					(size 1 1)
					(thickness 0.15)
				)
				(justify mirror)
			)
		)
		(property "Manufacturer" "Samsung Electro-Mechanics"
			(at 0 0 90)
			(unlocked yes)
			(layer "B.Fab")
			(hide yes)
			(effects
				(font
					(size 1 1)
					(thickness 0.15)
				)
				(justify mirror)
			)
		)
		(property "License" "Apache-2.0"
			(at 0 0 90)
			(unlocked yes)
			(layer "B.Fab")
			(hide yes)
			(effects
				(font
					(size 1 1)
					(thickness 0.15)
				)
				(justify mirror)
			)
		)
		(property "Author" "Antmicro"
			(at 0 0 90)
			(unlocked yes)
			(layer "B.Fab")
			(hide yes)
			(effects
				(font
					(size 1 1)
					(thickness 0.15)
				)
				(justify mirror)
			)
		)
		(property "Public" "False"
			(at 0 0 90)
			(unlocked yes)
			(layer "B.Fab")
			(hide yes)
			(effects
				(font
					(size 1 1)
					(thickness 0.15)
				)
				(justify mirror)
			)
		)
		(sheetname "/Expansion connector/")
		(sheetfile "expansion_connector.kicad_sch")
		(attr smd)
		(fp_line
			(start -0.3 -0.7)
			(end 0.3 -0.7)
			(stroke
				(width 0.15)
				(type solid)
			)
			(layer "B.SilkS")
		)
		(fp_line
			(start -0.3 0.7)
			(end 0.3 0.7)
			(stroke
				(width 0.15)
				(type solid)
			)
			(layer "B.SilkS")
		)
		(fp_poly
			(pts
				(xy 1.95 0.9) (xy -1.95 0.9) (xy -1.95 -0.9) (xy 1.95 -0.9)
			)
			(stroke
				(width 0.05)
				(type default)
			)
			(fill no)
			(layer "B.CrtYd")
		)
		(fp_poly
			(pts
				(xy -0.95 0.675001) (xy 0.95 0.675001) (xy 0.95 -0.675001) (xy -0.95 -0.675001)
			)
			(stroke
				(width 0.15)
				(type solid)
			)
			(fill no)
			(layer "B.Fab")
		)
		(fp_text user "Author: Antmicro"
			(at -1.9 -5.947 90)
			(layer "B.Fab")
			(effects
				(font
					(size 0.7 0.7)
					(thickness 0.15)
				)
				(justify right top mirror)
			)
		)
		(fp_text user "License: Apache-2.0"
			(at -1.9 -4.947 90)
			(layer "B.Fab")
			(effects
				(font
					(size 0.7 0.7)
					(thickness 0.15)
				)
				(justify right top mirror)
			)
		)
		(fp_text user "${REFERENCE}"
			(at -1.899999 -3.947 90)
			(layer "B.Fab")
			(effects
				(font
					(size 0.7 0.7)
					(thickness 0.15)
				)
				(justify right top mirror)
			)
		)
		(pad "1" smd roundrect
			(at -1.099999 0 90)
			(size 1.2 1.3)
			(layers "B.Cu" "B.Mask" "B.Paste")
			(roundrect_rratio 0.25)
			(net 1 "GND")
			(pintype "passive")
		)
		(pad "2" smd roundrect
			(at 1.099999 0 90)
			(size 1.2 1.3)
			(layers "B.Cu" "B.Mask" "B.Paste")
			(roundrect_rratio 0.25)
			(net 156 "/Expansion connector/+VCC_FMC")
			(pintype "passive")
		)
	)
)
